# T6G (Grand Teton) — schematic netlist excerpt (pin names and nets, part order shuffled) for the footprints in the layout excerpt that follows; sources: Cadence DE-HDL packaged netlist, KiCad conversion of 04192023_DAF0TMB3IC0_F0TG_MB_C_brd_V02_OCP.brd

R3271  Q_RES  1K 1% EMPTY  pkg 0402LF  page 111 : A = P3V3_AUX ; B = FM_P2E_EQA1
R568  Q_RES  10K 1% CHIP  pkg 0402LF  page 188 : A = P12V_AUX ; B = SW_P3V3_EN_ISO_R
R836  Q_RES  1K 1% CHIP  pkg 0201LF  page 185 : A = P1V8_CPU0_RT_1D ; B = SMB_RT_CPU0_P1_ROM_R_SDA

(kicad_pcb
	(version 20260206)
	(generator "pcbnew")
	(generator_version "10.0")
	(general
		(thickness 1.6)
		(legacy_teardrops no)
	)
	(paper "A4")
	(title_block
		(title "04192023_DAF0TMB3IC0_F0TG_MB_C_brd_V02_OCP.brd")
		(comment 1 "Grand Teton / footprints 4015-4017 of 8354")
	)
	(layers
		(0 "F.Cu" signal "TOP")
		(4 "In1.Cu" signal "GND")
		(6 "In2.Cu" signal "IN1")
		(8 "In3.Cu" signal "GND1")
		(10 "In4.Cu" signal "IN2")
		(12 "In5.Cu" signal "GND2")
		(14 "In6.Cu" signal "IN3")
		(16 "In7.Cu" signal "GND3")
		(18 "In8.Cu" signal "VCC")
		(20 "In9.Cu" signal "VCC1")
		(22 "In10.Cu" signal "GND4")
		(24 "In11.Cu" signal "IN4")
		(26 "In12.Cu" signal "GND5")
		(28 "In13.Cu" signal "IN5")
		(30 "In14.Cu" signal "GND6")
		(32 "In15.Cu" signal "IN6")
		(34 "In16.Cu" signal "GND7")
		(2 "B.Cu" signal "BOTTOM")
		(9 "F.Adhes" user "F.Adhesive")
		(11 "B.Adhes" user "B.Adhesive")
		(13 "F.Paste" user "Package Geometry/Pastemask Top")
		(15 "B.Paste" user "Package Geometry/Pastemask Bottom")
		(5 "F.SilkS" user "Ref Des/Silkscreen Top")
		(7 "B.SilkS" user "Ref Des/Silkscreen Bottom")
		(1 "F.Mask" user "Board Geometry/Soldermask Top")
		(3 "B.Mask" user "Board Geometry/Soldermask Bottom")
		(17 "Dwgs.User" user "User.Drawings")
		(19 "Cmts.User" user "User.Comments")
		(21 "Eco1.User" user "User.Eco1")
		(23 "Eco2.User" user "User.Eco2")
		(25 "Edge.Cuts" user "Board Geometry/Outline")
		(27 "Margin" user)
		(31 "F.CrtYd" user "Package Geometry/Place Bound Top")
		(29 "B.CrtYd" user "Package Geometry/Place Bound Bottom")
		(35 "F.Fab" user "Ref Des/Assembly Top")
		(33 "B.Fab" user "Ref Des/Assembly Bottom")
	)
	(footprint ""
		(layer "F.Cu")
		(at 211.074 -129.54 -90)
		(property "Reference" "R568"
			(at 0 0 270)
			(layer "F.SilkS")
			(hide yes)
			(effects
				(font
					(size 1.27 1.27)
				)
			)
		)
		(property "Value" ""
			(at 0 0 270)
			(layer "F.Fab")
			(effects
				(font
					(size 1.27 1.27)
				)
			)
		)
		(duplicate_pad_numbers_are_jumpers no)
		(fp_line
			(start -0.7874 0.4064)
			(end -0.7874 -0.4064)
			(stroke
				(width 0.1524)
				(type default)
			)
			(layer "F.SilkS")
		)
		(fp_line
			(start 0.7874 0.4064)
			(end -0.7874 0.4064)
			(stroke
				(width 0.1524)
				(type default)
			)
			(layer "F.SilkS")
		)
		(fp_line
			(start -0.7874 -0.4064)
			(end 0.7874 -0.4064)
			(stroke
				(width 0.1524)
				(type default)
			)
			(layer "F.SilkS")
		)
		(fp_line
			(start 0.7874 -0.4064)
			(end 0.7874 0.4064)
			(stroke
				(width 0.1524)
				(type default)
			)
			(layer "F.SilkS")
		)
		(fp_line
			(start -0.67945 0.3048)
			(end -0.67945 -0.305054)
			(stroke
				(width 0.1)
				(type default)
			)
			(layer "F.Fab")
		)
		(fp_line
			(start -0.12065 0.3048)
			(end -0.67945 0.3048)
			(stroke
				(width 0.1)
				(type default)
			)
			(layer "F.Fab")
		)
		(fp_line
			(start 0.120396 0.3048)
			(end 0.120396 0.2794)
			(stroke
				(width 0.1)
				(type default)
			)
			(layer "F.Fab")
		)
		(fp_line
			(start 0.67945 0.3048)
			(end 0.120396 0.3048)
			(stroke
				(width 0.1)
				(type default)
			)
			(layer "F.Fab")
		)
		(fp_line
			(start -0.12065 0.2794)
			(end -0.12065 0.3048)
			(stroke
				(width 0.1)
				(type default)
			)
			(layer "F.Fab")
		)
		(fp_line
			(start 0.120396 0.2794)
			(end -0.12065 0.2794)
			(stroke
				(width 0.1)
				(type default)
			)
			(layer "F.Fab")
		)
		(fp_line
			(start -0.12065 -0.2794)
			(end 0.12065 -0.2794)
			(stroke
				(width 0.1)
				(type default)
			)
			(layer "F.Fab")
		)
		(fp_line
			(start 0.12065 -0.2794)
			(end 0.12065 -0.3048)
			(stroke
				(width 0.1)
				(type default)
			)
			(layer "F.Fab")
		)
		(fp_line
			(start 0.12065 -0.3048)
			(end 0.67945 -0.3048)
			(stroke
				(width 0.1)
				(type default)
			)
			(layer "F.Fab")
		)
		(fp_line
			(start 0.67945 -0.3048)
			(end 0.67945 0.3048)
			(stroke
				(width 0.1)
				(type default)
			)
			(layer "F.Fab")
		)
		(fp_line
			(start -0.67945 -0.305054)
			(end -0.12065 -0.305054)
			(stroke
				(width 0.1)
				(type default)
			)
			(layer "F.Fab")
		)
		(fp_line
			(start -0.12065 -0.305054)
			(end -0.12065 -0.2794)
			(stroke
				(width 0.1)
				(type default)
			)
			(layer "F.Fab")
		)
		(pad "1" smd circle
			(at -0.40005 0 270)
			(size 0 0)
			(layers "F.Cu" "F.Mask" "F.Paste")
			(net "P12V_AUX")
		)
		(pad "2" smd circle
			(at 0.40005 0 270)
			(size 0 0)
			(layers "F.Cu" "F.Mask" "F.Paste")
			(net "SW_P3V3_EN_ISO_R")
		)
	)
	(footprint ""
		(layer "F.Cu")
		(at 291.509958 -397.59001 180)
		(property "Reference" "R836"
			(at 0 0 180)
			(layer "F.SilkS")
			(hide yes)
			(effects
				(font
					(size 1.27 1.27)
				)
			)
		)
		(property "Value" ""
			(at 0 0 180)
			(layer "F.Fab")
			(effects
				(font
					(size 1.27 1.27)
				)
			)
		)
		(duplicate_pad_numbers_are_jumpers no)
		(fp_line
			(start 0.32512 0.175006)
			(end -0.32512 0.175006)
			(stroke
				(width 0.1)
				(type default)
			)
			(layer "F.Fab")
		)
		(fp_line
			(start 0.32512 -0.175006)
			(end 0.32512 0.175006)
			(stroke
				(width 0.1)
				(type default)
			)
			(layer "F.Fab")
		)
		(fp_line
			(start -0.32512 0.175006)
			(end -0.32512 -0.175006)
			(stroke
				(width 0.1)
				(type default)
			)
			(layer "F.Fab")
		)
		(fp_line
			(start -0.32512 -0.175006)
			(end 0.32512 -0.175006)
			(stroke
				(width 0.1)
				(type default)
			)
			(layer "F.Fab")
		)
		(pad "1" smd rect
			(at -0.2667 0 180)
			(size 0.3048 0.381)
			(layers "F.Cu" "F.Mask" "F.Paste")
			(net "P1V8_CPU0_RT_1D")
		)
		(pad "2" smd rect
			(at 0.2667 0)
			(size 0.3048 0.381)
			(layers "F.Cu" "F.Mask" "F.Paste")
			(net "SMB_RT_CPU0_P1_ROM_R_SDA")
		)
	)
	(footprint ""
		(layer "F.Cu")
		(at 28.537662 -419.249098 90)
		(property "Reference" "R3271"
			(at 0 0 90)
			(layer "F.SilkS")
			(hide yes)
			(effects
				(font
					(size 1.27 1.27)
				)
			)
		)
		(property "Value" ""
			(at 0 0 90)
			(layer "F.Fab")
			(effects
				(font
					(size 1.27 1.27)
				)
			)
		)
		(duplicate_pad_numbers_are_jumpers no)
		(fp_line
			(start 0.7874 -0.4064)
			(end 0.7874 0.4064)
			(stroke
				(width 0.1524)
				(type default)
			)
			(layer "F.SilkS")
		)
		(fp_line
			(start -0.7874 -0.4064)
			(end 0.7874 -0.4064)
			(stroke
				(width 0.1524)
				(type default)
			)
			(layer "F.SilkS")
		)
		(fp_line
			(start 0.7874 0.4064)
			(end -0.7874 0.4064)
			(stroke
				(width 0.1524)
				(type default)
			)
			(layer "F.SilkS")
		)
		(fp_line
			(start -0.7874 0.4064)
			(end -0.7874 -0.4064)
			(stroke
				(width 0.1524)
				(type default)
			)
			(layer "F.SilkS")
		)
		(fp_line
			(start -0.12065 -0.305054)
			(end -0.12065 -0.2794)
			(stroke
				(width 0.1)
				(type default)
			)
			(layer "F.Fab")
		)
		(fp_line
			(start -0.67945 -0.305054)
			(end -0.12065 -0.305054)
			(stroke
				(width 0.1)
				(type default)
			)
			(layer "F.Fab")
		)
		(fp_line
			(start 0.67945 -0.3048)
			(end 0.67945 0.3048)
			(stroke
				(width 0.1)
				(type default)
			)
			(layer "F.Fab")
		)
		(fp_line
			(start 0.12065 -0.3048)
			(end 0.67945 -0.3048)
			(stroke
				(width 0.1)
				(type default)
			)
			(layer "F.Fab")
		)
		(fp_line
			(start 0.12065 -0.2794)
			(end 0.12065 -0.3048)
			(stroke
				(width 0.1)
				(type default)
			)
			(layer "F.Fab")
		)
		(fp_line
			(start -0.12065 -0.2794)
			(end 0.12065 -0.2794)
			(stroke
				(width 0.1)
				(type default)
			)
			(layer "F.Fab")
		)
		(fp_line
			(start 0.120396 0.2794)
			(end -0.12065 0.2794)
			(stroke
				(width 0.1)
				(type default)
			)
			(layer "F.Fab")
		)
		(fp_line
			(start -0.12065 0.2794)
			(end -0.12065 0.3048)
			(stroke
				(width 0.1)
				(type default)
			)
			(layer "F.Fab")
		)
		(fp_line
			(start 0.67945 0.3048)
			(end 0.120396 0.3048)
			(stroke
				(width 0.1)
				(type default)
			)
			(layer "F.Fab")
		)
		(fp_line
			(start 0.120396 0.3048)
			(end 0.120396 0.2794)
			(stroke
				(width 0.1)
				(type default)
			)
			(layer "F.Fab")
		)
		(fp_line
			(start -0.12065 0.3048)
			(end -0.67945 0.3048)
			(stroke
				(width 0.1)
				(type default)
			)
			(layer "F.Fab")
		)
		(fp_line
			(start -0.67945 0.3048)
			(end -0.67945 -0.305054)
			(stroke
				(width 0.1)
				(type default)
			)
			(layer "F.Fab")
		)
		(pad "1" smd circle
			(at -0.40005 0 90)
			(size 0 0)
			(layers "F.Cu" "F.Mask" "F.Paste")
			(net "P3V3_AUX")
		)
		(pad "2" smd circle
			(at 0.40005 0 90)
			(size 0 0)
			(layers "F.Cu" "F.Mask" "F.Paste")
			(net "FM_P2E_EQA1")
		)
	)
)
